# T6G (Grand Teton) — schematic netlist excerpt (pin names and nets, part order shuffled) for the footprints in the layout excerpt that follows; sources: Cadence DE-HDL packaged netlist, KiCad conversion of 04192023_DAF0TMB3IC0_F0TG_MB_C_brd_V02_OCP.brd

R850  Q_RES  0 5% CHIP  pkg 0201LF  page 185 : A = SMB_MUX_RT_ROM_SDA ; B = SMB_MUX_RT_ROM_R1_SDA

Q96  MOSFET_NCH_DUAL  PJT138K IC  pkg SOT363XD  page 127
  S1  = GND
  G1  = GPU_FPGA_READY
  D2  = GPU_FPGA_READY_ISO
  S2  = GND
  G2  = GPU_FPGA_READY_N
  D1  = GPU_FPGA_READY_N

PR265  Q_RES  2.2 1% CHIP  pkg 0402LF  page 219 : A = PVDDCR_CPU1_P1_PVCC ; B = PVDDCR_CPU1_P1_VCC3

(kicad_pcb
	(version 20260206)
	(generator "pcbnew")
	(generator_version "10.0")
	(general
		(thickness 1.6)
		(legacy_teardrops no)
	)
	(paper "A4")
	(title_block
		(title "04192023_DAF0TMB3IC0_F0TG_MB_C_brd_V02_OCP.brd")
		(comment 1 "Grand Teton / footprints 5084-5086 of 8354")
	)
	(layers
		(0 "F.Cu" signal "TOP")
		(4 "In1.Cu" signal "GND")
		(6 "In2.Cu" signal "IN1")
		(8 "In3.Cu" signal "GND1")
		(10 "In4.Cu" signal "IN2")
		(12 "In5.Cu" signal "GND2")
		(14 "In6.Cu" signal "IN3")
		(16 "In7.Cu" signal "GND3")
		(18 "In8.Cu" signal "VCC")
		(20 "In9.Cu" signal "VCC1")
		(22 "In10.Cu" signal "GND4")
		(24 "In11.Cu" signal "IN4")
		(26 "In12.Cu" signal "GND5")
		(28 "In13.Cu" signal "IN5")
		(30 "In14.Cu" signal "GND6")
		(32 "In15.Cu" signal "IN6")
		(34 "In16.Cu" signal "GND7")
		(2 "B.Cu" signal "BOTTOM")
		(9 "F.Adhes" user "F.Adhesive")
		(11 "B.Adhes" user "B.Adhesive")
		(13 "F.Paste" user "Package Geometry/Pastemask Top")
		(15 "B.Paste" user "Package Geometry/Pastemask Bottom")
		(5 "F.SilkS" user "Ref Des/Silkscreen Top")
		(7 "B.SilkS" user "Ref Des/Silkscreen Bottom")
		(1 "F.Mask" user "Board Geometry/Soldermask Top")
		(3 "B.Mask" user "Board Geometry/Soldermask Bottom")
		(17 "Dwgs.User" user "User.Drawings")
		(19 "Cmts.User" user "User.Comments")
		(21 "Eco1.User" user "User.Eco1")
		(23 "Eco2.User" user "User.Eco2")
		(25 "Edge.Cuts" user "Board Geometry/Outline")
		(27 "Margin" user)
		(31 "F.CrtYd" user "Package Geometry/Place Bound Top")
		(29 "B.CrtYd" user "Package Geometry/Place Bound Bottom")
		(35 "F.Fab" user "Ref Des/Assembly Top")
		(33 "B.Fab" user "Ref Des/Assembly Bottom")
	)
	(footprint ""
		(layer "B.Cu")
		(at 48.618902 -421.460676)
		(property "Reference" "Q96"
			(at 0.70104 -1.773682 0)
			(unlocked yes)
			(layer "B.SilkS")
			(effects
				(font
					(size 0.7874 0.5842)
					(thickness 0.1524)
				)
				(justify left mirror)
			)
		)
		(property "Value" ""
			(at 0 0 0)
			(layer "B.Fab")
			(effects
				(font
					(size 1.27 1.27)
				)
				(justify mirror)
			)
		)
		(duplicate_pad_numbers_are_jumpers no)
		(fp_line
			(start -1.332738 -1.100074)
			(end -1.332738 1.100074)
			(stroke
				(width 0.1524)
				(type default)
			)
			(layer "B.SilkS")
		)
		(fp_line
			(start -1.332738 1.100074)
			(end 1.332738 1.100074)
			(stroke
				(width 0.1524)
				(type default)
			)
			(layer "B.SilkS")
		)
		(fp_line
			(start -0.4826 -1.100074)
			(end -1.332738 -1.100074)
			(stroke
				(width 0.1524)
				(type default)
			)
			(layer "B.SilkS")
		)
		(fp_line
			(start 0 -0.541274)
			(end -0.4826 -1.100074)
			(stroke
				(width 0.1524)
				(type default)
			)
			(layer "B.SilkS")
		)
		(fp_line
			(start 0.4826 -1.100074)
			(end 0 -0.541274)
			(stroke
				(width 0.1524)
				(type default)
			)
			(layer "B.SilkS")
		)
		(fp_line
			(start 1.332738 -1.100074)
			(end 0.4826 -1.100074)
			(stroke
				(width 0.1524)
				(type default)
			)
			(layer "B.SilkS")
		)
		(fp_line
			(start 1.332738 1.100074)
			(end 1.332738 -1.100074)
			(stroke
				(width 0.1524)
				(type default)
			)
			(layer "B.SilkS")
		)
		(fp_poly
			(pts
				(xy 1.039114 -1.794002) (xy 1.373378 -2.504186) (xy 0.671576 -2.487676)
			)
			(stroke
				(width 0)
				(type default)
			)
			(fill yes)
			(layer "B.SilkS")
		)
		(fp_line
			(start -0.674878 -1.100074)
			(end -0.674878 1.100074)
			(stroke
				(width 0.1)
				(type default)
			)
			(layer "B.Fab")
		)
		(fp_line
			(start -0.674878 1.100074)
			(end 0.674878 1.100074)
			(stroke
				(width 0.1)
				(type default)
			)
			(layer "B.Fab")
		)
		(fp_line
			(start 0.674878 -1.100074)
			(end -0.674878 -1.100074)
			(stroke
				(width 0.1)
				(type default)
			)
			(layer "B.Fab")
		)
		(fp_line
			(start 0.674878 1.100074)
			(end 0.674878 -1.100074)
			(stroke
				(width 0.1)
				(type default)
			)
			(layer "B.Fab")
		)
		(fp_poly
			(pts
				(xy 2.2352 -0.298958) (xy 2.2352 -1.001014) (xy 1.533144 -0.649986)
			)
			(stroke
				(width 0)
				(type default)
			)
			(fill yes)
			(layer "B.Fab")
		)
		(pad "1" smd rect
			(at 0.94996 -0.649986 90)
			(size 0.4318 0.508)
			(layers "B.Cu" "B.Mask" "B.Paste")
			(net "GND")
		)
		(pad "2" smd rect
			(at 0.94996 0 90)
			(size 0.4318 0.508)
			(layers "B.Cu" "B.Mask" "B.Paste")
			(net "GPU_FPGA_READY")
		)
		(pad "3" smd rect
			(at 0.94996 0.649986 90)
			(size 0.4318 0.508)
			(layers "B.Cu" "B.Mask" "B.Paste")
			(net "GPU_FPGA_READY_ISO")
		)
		(pad "4" smd rect
			(at -0.94996 0.649986 90)
			(size 0.4318 0.508)
			(layers "B.Cu" "B.Mask" "B.Paste")
			(net "GND")
		)
		(pad "5" smd rect
			(at -0.94996 0 90)
			(size 0.4318 0.508)
			(layers "B.Cu" "B.Mask" "B.Paste")
			(net "GPU_FPGA_READY_N")
		)
		(pad "6" smd rect
			(at -0.94996 -0.649986 90)
			(size 0.4318 0.508)
			(layers "B.Cu" "B.Mask" "B.Paste")
			(net "GPU_FPGA_READY_N")
		)
	)
	(footprint ""
		(layer "B.Cu")
		(at 254.635 -330.962 180)
		(property "Reference" "R850"
			(at 0 0 0)
			(layer "B.SilkS")
			(hide yes)
			(effects
				(font
					(size 1.27 1.27)
				)
				(justify mirror)
			)
		)
		(property "Value" ""
			(at 0 0 0)
			(layer "B.Fab")
			(effects
				(font
					(size 1.27 1.27)
				)
				(justify mirror)
			)
		)
		(duplicate_pad_numbers_are_jumpers no)
		(fp_line
			(start 0.32512 0.175006)
			(end 0.32512 -0.175006)
			(stroke
				(width 0.1)
				(type default)
			)
			(layer "B.Fab")
		)
		(fp_line
			(start 0.32512 -0.175006)
			(end -0.32512 -0.175006)
			(stroke
				(width 0.1)
				(type default)
			)
			(layer "B.Fab")
		)
		(fp_line
			(start -0.32512 0.175006)
			(end 0.32512 0.175006)
			(stroke
				(width 0.1)
				(type default)
			)
			(layer "B.Fab")
		)
		(fp_line
			(start -0.32512 -0.175006)
			(end -0.32512 0.175006)
			(stroke
				(width 0.1)
				(type default)
			)
			(layer "B.Fab")
		)
		(pad "1" smd rect
			(at 0.2667 0)
			(size 0.3048 0.381)
			(layers "B.Cu" "B.Mask" "B.Paste")
			(net "SMB_MUX_RT_ROM_SDA")
		)
		(pad "2" smd rect
			(at -0.2667 0 180)
			(size 0.3048 0.381)
			(layers "B.Cu" "B.Mask" "B.Paste")
			(net "SMB_MUX_RT_ROM_R1_SDA")
		)
	)
	(footprint ""
		(layer "B.Cu")
		(at 68.098162 -336.059272 -90)
		(property "Reference" "PR265"
			(at 0 0 90)
			(layer "B.SilkS")
			(hide yes)
			(effects
				(font
					(size 1.27 1.27)
				)
				(justify mirror)
			)
		)
		(property "Value" ""
			(at 0 0 90)
			(layer "B.Fab")
			(effects
				(font
					(size 1.27 1.27)
				)
				(justify mirror)
			)
		)
		(duplicate_pad_numbers_are_jumpers no)
		(fp_line
			(start -0.7874 0.4064)
			(end 0.7874 0.4064)
			(stroke
				(width 0.1524)
				(type default)
			)
			(layer "B.SilkS")
		)
		(fp_line
			(start 0.7874 0.4064)
			(end 0.7874 -0.4064)
			(stroke
				(width 0.1524)
				(type default)
			)
			(layer "B.SilkS")
		)
		(fp_line
			(start -0.7874 -0.4064)
			(end -0.7874 0.4064)
			(stroke
				(width 0.1524)
				(type default)
			)
			(layer "B.SilkS")
		)
		(fp_line
			(start 0.7874 -0.4064)
			(end -0.7874 -0.4064)
			(stroke
				(width 0.1524)
				(type default)
			)
			(layer "B.SilkS")
		)
		(fp_line
			(start -0.67945 0.3048)
			(end -0.120396 0.3048)
			(stroke
				(width 0.1)
				(type default)
			)
			(layer "B.Fab")
		)
		(fp_line
			(start -0.120396 0.3048)
			(end -0.120396 0.2794)
			(stroke
				(width 0.1)
				(type default)
			)
			(layer "B.Fab")
		)
		(fp_line
			(start 0.12065 0.3048)
			(end 0.67945 0.3048)
			(stroke
				(width 0.1)
				(type default)
			)
			(layer "B.Fab")
		)
		(fp_line
			(start 0.67945 0.3048)
			(end 0.67945 -0.305054)
			(stroke
				(width 0.1)
				(type default)
			)
			(layer "B.Fab")
		)
		(fp_line
			(start -0.120396 0.2794)
			(end 0.12065 0.2794)
			(stroke
				(width 0.1)
				(type default)
			)
			(layer "B.Fab")
		)
		(fp_line
			(start 0.12065 0.2794)
			(end 0.12065 0.3048)
			(stroke
				(width 0.1)
				(type default)
			)
			(layer "B.Fab")
		)
		(fp_line
			(start -0.12065 -0.2794)
			(end -0.12065 -0.3048)
			(stroke
				(width 0.1)
				(type default)
			)
			(layer "B.Fab")
		)
		(fp_line
			(start 0.12065 -0.2794)
			(end -0.12065 -0.2794)
			(stroke
				(width 0.1)
				(type default)
			)
			(layer "B.Fab")
		)
		(fp_line
			(start -0.67945 -0.3048)
			(end -0.67945 0.3048)
			(stroke
				(width 0.1)
				(type default)
			)
			(layer "B.Fab")
		)
		(fp_line
			(start -0.12065 -0.3048)
			(end -0.67945 -0.3048)
			(stroke
				(width 0.1)
				(type default)
			)
			(layer "B.Fab")
		)
		(fp_line
			(start 0.12065 -0.305054)
			(end 0.12065 -0.2794)
			(stroke
				(width 0.1)
				(type default)
			)
			(layer "B.Fab")
		)
		(fp_line
			(start 0.67945 -0.305054)
			(end 0.12065 -0.305054)
			(stroke
				(width 0.1)
				(type default)
			)
			(layer "B.Fab")
		)
		(pad "1" smd circle
			(at 0.40005 0 90)
			(size 0 0)
			(layers "B.Cu" "B.Mask" "B.Paste")
			(net "PVDDCR_CPU1_P1_PVCC")
		)
		(pad "2" smd circle
			(at -0.40005 0 90)
			(size 0 0)
			(layers "B.Cu" "B.Mask" "B.Paste")
			(net "PVDDCR_CPU1_P1_VCC3")
		)
	)
)
